(kicad_pcb
	(version 20260206)
	(generator "pcbnew")
	(generator_version "10.0")
	(general
		(thickness 1.6)
		(legacy_teardrops no)
	)
	(paper "A4")
	(title_block
		(title "01162023_DA0F0TEBIF0_F0T_Expander_BD_F_brd_V02_OCP.brd")
		(comment 1 "Grand Teton / footprints 6754-6759 of 9728")
	)
	(layers
		(0 "F.Cu" signal "TOP")
		(4 "In1.Cu" signal "GND")
		(6 "In2.Cu" signal "VCC")
		(8 "In3.Cu" signal "VCC1")
		(10 "In4.Cu" signal "GND1")
		(12 "In5.Cu" signal "IN1")
		(14 "In6.Cu" signal "GND2")
		(16 "In7.Cu" signal "IN2")
		(18 "In8.Cu" signal "GND3")
		(20 "In9.Cu" signal "IN3")
		(22 "In10.Cu" signal "GND4")
		(24 "In11.Cu" signal "IN4")
		(26 "In12.Cu" signal "GND5")
		(28 "In13.Cu" signal "IN5")
		(30 "In14.Cu" signal "GND6")
		(32 "In15.Cu" signal "IN6")
		(34 "In16.Cu" signal "GND7")
		(2 "B.Cu" signal "BOTTOM")
		(9 "F.Adhes" user "F.Adhesive")
		(11 "B.Adhes" user "B.Adhesive")
		(13 "F.Paste" user "Package Geometry/Pastemask Top")
		(15 "B.Paste" user "Package Geometry/Pastemask Bottom")
		(5 "F.SilkS" user "Ref Des/Silkscreen Top")
		(7 "B.SilkS" user "Ref Des/Silkscreen Bottom")
		(1 "F.Mask" user "Board Geometry/Soldermask Top")
		(3 "B.Mask" user "Board Geometry/Soldermask Bottom")
		(17 "Dwgs.User" user "User.Drawings")
		(19 "Cmts.User" user "User.Comments")
		(21 "Eco1.User" user "User.Eco1")
		(23 "Eco2.User" user "User.Eco2")
		(25 "Edge.Cuts" user "Board Geometry/Outline")
		(27 "Margin" user)
		(31 "F.CrtYd" user "Package Geometry/Place Bound Top")
		(29 "B.CrtYd" user "Package Geometry/Place Bound Bottom")
		(35 "F.Fab" user "Ref Des/Assembly Top")
		(33 "B.Fab" user "Ref Des/Assembly Bottom")
	)
	(footprint ""
		(layer "F.Cu")
		(at 404.18004 -141.9352)
		(property "Reference" "R316"
			(at 0 0 0)
			(layer "F.SilkS")
			(hide yes)
			(effects
				(font
					(size 1.27 1.27)
				)
			)
		)
		(property "Value" ""
			(at 0 0 0)
			(layer "F.Fab")
			(effects
				(font
					(size 1.27 1.27)
				)
			)
		)
		(duplicate_pad_numbers_are_jumpers no)
		(fp_line
			(start -0.7874 -0.4064)
			(end 0.7874 -0.4064)
			(stroke
				(width 0.1524)
				(type default)
			)
			(layer "F.SilkS")
		)
		(fp_line
			(start -0.7874 0.4064)
			(end -0.7874 -0.4064)
			(stroke
				(width 0.1524)
				(type default)
			)
			(layer "F.SilkS")
		)
		(fp_line
			(start 0.7874 -0.4064)
			(end 0.7874 0.4064)
			(stroke
				(width 0.1524)
				(type default)
			)
			(layer "F.SilkS")
		)
		(fp_line
			(start 0.7874 0.4064)
			(end -0.7874 0.4064)
			(stroke
				(width 0.1524)
				(type default)
			)
			(layer "F.SilkS")
		)
		(fp_line
			(start -0.67945 -0.305054)
			(end -0.12065 -0.305054)
			(stroke
				(width 0.1)
				(type default)
			)
			(layer "F.Fab")
		)
		(fp_line
			(start -0.67945 0.3048)
			(end -0.67945 -0.305054)
			(stroke
				(width 0.1)
				(type default)
			)
			(layer "F.Fab")
		)
		(fp_line
			(start -0.12065 -0.305054)
			(end -0.12065 -0.2794)
			(stroke
				(width 0.1)
				(type default)
			)
			(layer "F.Fab")
		)
		(fp_line
			(start -0.12065 -0.2794)
			(end 0.12065 -0.2794)
			(stroke
				(width 0.1)
				(type default)
			)
			(layer "F.Fab")
		)
		(fp_line
			(start -0.12065 0.2794)
			(end -0.12065 0.3048)
			(stroke
				(width 0.1)
				(type default)
			)
			(layer "F.Fab")
		)
		(fp_line
			(start -0.12065 0.3048)
			(end -0.67945 0.3048)
			(stroke
				(width 0.1)
				(type default)
			)
			(layer "F.Fab")
		)
		(fp_line
			(start 0.120396 0.2794)
			(end -0.12065 0.2794)
			(stroke
				(width 0.1)
				(type default)
			)
			(layer "F.Fab")
		)
		(fp_line
			(start 0.120396 0.3048)
			(end 0.120396 0.2794)
			(stroke
				(width 0.1)
				(type default)
			)
			(layer "F.Fab")
		)
		(fp_line
			(start 0.12065 -0.3048)
			(end 0.67945 -0.3048)
			(stroke
				(width 0.1)
				(type default)
			)
			(layer "F.Fab")
		)
		(fp_line
			(start 0.12065 -0.2794)
			(end 0.12065 -0.3048)
			(stroke
				(width 0.1)
				(type default)
			)
			(layer "F.Fab")
		)
		(fp_line
			(start 0.67945 -0.3048)
			(end 0.67945 0.3048)
			(stroke
				(width 0.1)
				(type default)
			)
			(layer "F.Fab")
		)
		(fp_line
			(start 0.67945 0.3048)
			(end 0.120396 0.3048)
			(stroke
				(width 0.1)
				(type default)
			)
			(layer "F.Fab")
		)
		(pad "1" smd circle
			(at -0.40005 0)
			(size 0 0)
			(layers "F.Cu" "F.Mask" "F.Paste")
			(net "SMB_NIC6_LS_SDA")
		)
		(pad "2" smd circle
			(at 0.40005 0)
			(size 0 0)
			(layers "F.Cu" "F.Mask" "F.Paste")
			(net "P3V3_NIC6")
		)
	)
	(footprint ""
		(layer "F.Cu")
		(at 145.697956 -197.2818)
		(property "Reference" "R6641"
			(at 0 0 0)
			(layer "F.SilkS")
			(hide yes)
			(effects
				(font
					(size 1.27 1.27)
				)
			)
		)
		(property "Value" ""
			(at 0 0 0)
			(layer "F.Fab")
			(effects
				(font
					(size 1.27 1.27)
				)
			)
		)
		(duplicate_pad_numbers_are_jumpers no)
		(fp_line
			(start -0.7874 -0.4064)
			(end 0.7874 -0.4064)
			(stroke
				(width 0.1524)
				(type default)
			)
			(layer "F.SilkS")
		)
		(fp_line
			(start -0.7874 0.4064)
			(end -0.7874 -0.4064)
			(stroke
				(width 0.1524)
				(type default)
			)
			(layer "F.SilkS")
		)
		(fp_line
			(start 0.7874 -0.4064)
			(end 0.7874 0.4064)
			(stroke
				(width 0.1524)
				(type default)
			)
			(layer "F.SilkS")
		)
		(fp_line
			(start 0.7874 0.4064)
			(end -0.7874 0.4064)
			(stroke
				(width 0.1524)
				(type default)
			)
			(layer "F.SilkS")
		)
		(fp_line
			(start -0.67945 -0.305054)
			(end -0.12065 -0.305054)
			(stroke
				(width 0.1)
				(type default)
			)
			(layer "F.Fab")
		)
		(fp_line
			(start -0.67945 0.3048)
			(end -0.67945 -0.305054)
			(stroke
				(width 0.1)
				(type default)
			)
			(layer "F.Fab")
		)
		(fp_line
			(start -0.12065 -0.305054)
			(end -0.12065 -0.2794)
			(stroke
				(width 0.1)
				(type default)
			)
			(layer "F.Fab")
		)
		(fp_line
			(start -0.12065 -0.2794)
			(end 0.12065 -0.2794)
			(stroke
				(width 0.1)
				(type default)
			)
			(layer "F.Fab")
		)
		(fp_line
			(start -0.12065 0.2794)
			(end -0.12065 0.3048)
			(stroke
				(width 0.1)
				(type default)
			)
			(layer "F.Fab")
		)
		(fp_line
			(start -0.12065 0.3048)
			(end -0.67945 0.3048)
			(stroke
				(width 0.1)
				(type default)
			)
			(layer "F.Fab")
		)
		(fp_line
			(start 0.120396 0.2794)
			(end -0.12065 0.2794)
			(stroke
				(width 0.1)
				(type default)
			)
			(layer "F.Fab")
		)
		(fp_line
			(start 0.120396 0.3048)
			(end 0.120396 0.2794)
			(stroke
				(width 0.1)
				(type default)
			)
			(layer "F.Fab")
		)
		(fp_line
			(start 0.12065 -0.3048)
			(end 0.67945 -0.3048)
			(stroke
				(width 0.1)
				(type default)
			)
			(layer "F.Fab")
		)
		(fp_line
			(start 0.12065 -0.2794)
			(end 0.12065 -0.3048)
			(stroke
				(width 0.1)
				(type default)
			)
			(layer "F.Fab")
		)
		(fp_line
			(start 0.67945 -0.3048)
			(end 0.67945 0.3048)
			(stroke
				(width 0.1)
				(type default)
			)
			(layer "F.Fab")
		)
		(fp_line
			(start 0.67945 0.3048)
			(end 0.120396 0.3048)
			(stroke
				(width 0.1)
				(type default)
			)
			(layer "F.Fab")
		)
		(pad "1" smd circle
			(at -0.40005 0)
			(size 0 0)
			(layers "F.Cu" "F.Mask" "F.Paste")
			(net "UART_PEX0_CLI_RX")
		)
		(pad "2" smd circle
			(at 0.40005 0)
			(size 0 0)
			(layers "F.Cu" "F.Mask" "F.Paste")
			(net "UART_PEX0_CLI_R_RX")
		)
	)
	(footprint ""
		(layer "F.Cu")
		(at 243.505228 -211.563712 90)
		(property "Reference" "R4893"
			(at 0 0 90)
			(layer "F.SilkS")
			(hide yes)
			(effects
				(font
					(size 1.27 1.27)
				)
			)
		)
		(property "Value" ""
			(at 0 0 90)
			(layer "F.Fab")
			(effects
				(font
					(size 1.27 1.27)
				)
			)
		)
		(duplicate_pad_numbers_are_jumpers no)
		(fp_line
			(start 0.7874 -0.4064)
			(end 0.7874 0.4064)
			(stroke
				(width 0.1524)
				(type default)
			)
			(layer "F.SilkS")
		)
		(fp_line
			(start -0.7874 -0.4064)
			(end 0.7874 -0.4064)
			(stroke
				(width 0.1524)
				(type default)
			)
			(layer "F.SilkS")
		)
		(fp_line
			(start 0.7874 0.4064)
			(end -0.7874 0.4064)
			(stroke
				(width 0.1524)
				(type default)
			)
			(layer "F.SilkS")
		)
		(fp_line
			(start -0.7874 0.4064)
			(end -0.7874 -0.4064)
			(stroke
				(width 0.1524)
				(type default)
			)
			(layer "F.SilkS")
		)
		(fp_line
			(start -0.12065 -0.305054)
			(end -0.12065 -0.2794)
			(stroke
				(width 0.1)
				(type default)
			)
			(layer "F.Fab")
		)
		(fp_line
			(start -0.67945 -0.305054)
			(end -0.12065 -0.305054)
			(stroke
				(width 0.1)
				(type default)
			)
			(layer "F.Fab")
		)
		(fp_line
			(start 0.67945 -0.3048)
			(end 0.67945 0.3048)
			(stroke
				(width 0.1)
				(type default)
			)
			(layer "F.Fab")
		)
		(fp_line
			(start 0.12065 -0.3048)
			(end 0.67945 -0.3048)
			(stroke
				(width 0.1)
				(type default)
			)
			(layer "F.Fab")
		)
		(fp_line
			(start 0.12065 -0.2794)
			(end 0.12065 -0.3048)
			(stroke
				(width 0.1)
				(type default)
			)
			(layer "F.Fab")
		)
		(fp_line
			(start -0.12065 -0.2794)
			(end 0.12065 -0.2794)
			(stroke
				(width 0.1)
				(type default)
			)
			(layer "F.Fab")
		)
		(fp_line
			(start 0.120396 0.2794)
			(end -0.12065 0.2794)
			(stroke
				(width 0.1)
				(type default)
			)
			(layer "F.Fab")
		)
		(fp_line
			(start -0.12065 0.2794)
			(end -0.12065 0.3048)
			(stroke
				(width 0.1)
				(type default)
			)
			(layer "F.Fab")
		)
		(fp_line
			(start 0.67945 0.3048)
			(end 0.120396 0.3048)
			(stroke
				(width 0.1)
				(type default)
			)
			(layer "F.Fab")
		)
		(fp_line
			(start 0.120396 0.3048)
			(end 0.120396 0.2794)
			(stroke
				(width 0.1)
				(type default)
			)
			(layer "F.Fab")
		)
		(fp_line
			(start -0.12065 0.3048)
			(end -0.67945 0.3048)
			(stroke
				(width 0.1)
				(type default)
			)
			(layer "F.Fab")
		)
		(fp_line
			(start -0.67945 0.3048)
			(end -0.67945 -0.305054)
			(stroke
				(width 0.1)
				(type default)
			)
			(layer "F.Fab")
		)
		(pad "1" smd circle
			(at -0.40005 0 90)
			(size 0 0)
			(layers "F.Cu" "F.Mask" "F.Paste")
			(net "JTAG_BIC_TDO_R")
		)
		(pad "2" smd circle
			(at 0.40005 0 90)
			(size 0 0)
			(layers "F.Cu" "F.Mask" "F.Paste")
			(net "JTAG_BIC_TDO_R1")
		)
	)
	(footprint ""
		(layer "F.Cu")
		(at 197.739508 -87.349076 -90)
		(property "Reference" "R198"
			(at 0 0 270)
			(layer "F.SilkS")
			(hide yes)
			(effects
				(font
					(size 1.27 1.27)
				)
			)
		)
		(property "Value" ""
			(at 0 0 270)
			(layer "F.Fab")
			(effects
				(font
					(size 1.27 1.27)
				)
			)
		)
		(duplicate_pad_numbers_are_jumpers no)
		(fp_line
			(start -0.7874 0.4064)
			(end -0.7874 -0.4064)
			(stroke
				(width 0.1524)
				(type default)
			)
			(layer "F.SilkS")
		)
		(fp_line
			(start 0.7874 0.4064)
			(end -0.7874 0.4064)
			(stroke
				(width 0.1524)
				(type default)
			)
			(layer "F.SilkS")
		)
		(fp_line
			(start -0.7874 -0.4064)
			(end 0.7874 -0.4064)
			(stroke
				(width 0.1524)
				(type default)
			)
			(layer "F.SilkS")
		)
		(fp_line
			(start 0.7874 -0.4064)
			(end 0.7874 0.4064)
			(stroke
				(width 0.1524)
				(type default)
			)
			(layer "F.SilkS")
		)
		(fp_line
			(start -0.67945 0.3048)
			(end -0.67945 -0.305054)
			(stroke
				(width 0.1)
				(type default)
			)
			(layer "F.Fab")
		)
		(fp_line
			(start -0.12065 0.3048)
			(end -0.67945 0.3048)
			(stroke
				(width 0.1)
				(type default)
			)
			(layer "F.Fab")
		)
		(fp_line
			(start 0.120396 0.3048)
			(end 0.120396 0.2794)
			(stroke
				(width 0.1)
				(type default)
			)
			(layer "F.Fab")
		)
		(fp_line
			(start 0.67945 0.3048)
			(end 0.120396 0.3048)
			(stroke
				(width 0.1)
				(type default)
			)
			(layer "F.Fab")
		)
		(fp_line
			(start -0.12065 0.2794)
			(end -0.12065 0.3048)
			(stroke
				(width 0.1)
				(type default)
			)
			(layer "F.Fab")
		)
		(fp_line
			(start 0.120396 0.2794)
			(end -0.12065 0.2794)
			(stroke
				(width 0.1)
				(type default)
			)
			(layer "F.Fab")
		)
		(fp_line
			(start -0.12065 -0.2794)
			(end 0.12065 -0.2794)
			(stroke
				(width 0.1)
				(type default)
			)
			(layer "F.Fab")
		)
		(fp_line
			(start 0.12065 -0.2794)
			(end 0.12065 -0.3048)
			(stroke
				(width 0.1)
				(type default)
			)
			(layer "F.Fab")
		)
		(fp_line
			(start 0.12065 -0.3048)
			(end 0.67945 -0.3048)
			(stroke
				(width 0.1)
				(type default)
			)
			(layer "F.Fab")
		)
		(fp_line
			(start 0.67945 -0.3048)
			(end 0.67945 0.3048)
			(stroke
				(width 0.1)
				(type default)
			)
			(layer "F.Fab")
		)
		(fp_line
			(start -0.67945 -0.305054)
			(end -0.12065 -0.305054)
			(stroke
				(width 0.1)
				(type default)
			)
			(layer "F.Fab")
		)
		(fp_line
			(start -0.12065 -0.305054)
			(end -0.12065 -0.2794)
			(stroke
				(width 0.1)
				(type default)
			)
			(layer "F.Fab")
		)
		(pad "1" smd circle
			(at -0.40005 0 270)
			(size 0 0)
			(layers "F.Cu" "F.Mask" "F.Paste")
			(net "RST_NIC3_PERST0_R_N")
		)
		(pad "2" smd circle
			(at 0.40005 0 270)
			(size 0 0)
			(layers "F.Cu" "F.Mask" "F.Paste")
			(net "RST_HP_NIC3_BUF_N")
		)
	)
	(footprint ""
		(layer "F.Cu")
		(at 264.611358 -286.844232 -90)
		(property "Reference" "R4584"
			(at 0 0 270)
			(layer "F.SilkS")
			(hide yes)
			(effects
				(font
					(size 1.27 1.27)
				)
			)
		)
		(property "Value" ""
			(at 0 0 270)
			(layer "F.Fab")
			(effects
				(font
					(size 1.27 1.27)
				)
			)
		)
		(duplicate_pad_numbers_are_jumpers no)
		(fp_line
			(start -0.7874 0.4064)
			(end -0.7874 -0.4064)
			(stroke
				(width 0.1524)
				(type default)
			)
			(layer "F.SilkS")
		)
		(fp_line
			(start 0.7874 0.4064)
			(end -0.7874 0.4064)
			(stroke
				(width 0.1524)
				(type default)
			)
			(layer "F.SilkS")
		)
		(fp_line
			(start -0.7874 -0.4064)
			(end 0.7874 -0.4064)
			(stroke
				(width 0.1524)
				(type default)
			)
			(layer "F.SilkS")
		)
		(fp_line
			(start 0.7874 -0.4064)
			(end 0.7874 0.4064)
			(stroke
				(width 0.1524)
				(type default)
			)
			(layer "F.SilkS")
		)
		(fp_line
			(start -0.67945 0.3048)
			(end -0.67945 -0.305054)
			(stroke
				(width 0.1)
				(type default)
			)
			(layer "F.Fab")
		)
		(fp_line
			(start -0.12065 0.3048)
			(end -0.67945 0.3048)
			(stroke
				(width 0.1)
				(type default)
			)
			(layer "F.Fab")
		)
		(fp_line
			(start 0.120396 0.3048)
			(end 0.120396 0.2794)
			(stroke
				(width 0.1)
				(type default)
			)
			(layer "F.Fab")
		)
		(fp_line
			(start 0.67945 0.3048)
			(end 0.120396 0.3048)
			(stroke
				(width 0.1)
				(type default)
			)
			(layer "F.Fab")
		)
		(fp_line
			(start -0.12065 0.2794)
			(end -0.12065 0.3048)
			(stroke
				(width 0.1)
				(type default)
			)
			(layer "F.Fab")
		)
		(fp_line
			(start 0.120396 0.2794)
			(end -0.12065 0.2794)
			(stroke
				(width 0.1)
				(type default)
			)
			(layer "F.Fab")
		)
		(fp_line
			(start -0.12065 -0.2794)
			(end 0.12065 -0.2794)
			(stroke
				(width 0.1)
				(type default)
			)
			(layer "F.Fab")
		)
		(fp_line
			(start 0.12065 -0.2794)
			(end 0.12065 -0.3048)
			(stroke
				(width 0.1)
				(type default)
			)
			(layer "F.Fab")
		)
		(fp_line
			(start 0.12065 -0.3048)
			(end 0.67945 -0.3048)
			(stroke
				(width 0.1)
				(type default)
			)
			(layer "F.Fab")
		)
		(fp_line
			(start 0.67945 -0.3048)
			(end 0.67945 0.3048)
			(stroke
				(width 0.1)
				(type default)
			)
			(layer "F.Fab")
		)
		(fp_line
			(start -0.67945 -0.305054)
			(end -0.12065 -0.305054)
			(stroke
				(width 0.1)
				(type default)
			)
			(layer "F.Fab")
		)
		(fp_line
			(start -0.12065 -0.305054)
			(end -0.12065 -0.2794)
			(stroke
				(width 0.1)
				(type default)
			)
			(layer "F.Fab")
		)
		(pad "1" smd circle
			(at -0.40005 0 270)
			(size 0 0)
			(layers "F.Cu" "F.Mask" "F.Paste")
			(net "PCEPLL6_VDDA18_PEX2")
		)
		(pad "2" smd circle
			(at 0.40005 0 270)
			(size 0 0)
			(layers "F.Cu" "F.Mask" "F.Paste")
			(net "PCEPLL6_VDDA18_PEX2_R")
		)
	)
	(footprint ""
		(layer "F.Cu")
		(at 352.232214 -155.321)
		(property "Reference" "R4821"
			(at 0 0 0)
			(layer "F.SilkS")
			(hide yes)
			(effects
				(font
					(size 1.27 1.27)
				)
			)
		)
		(property "Value" ""
			(at 0 0 0)
			(layer "F.Fab")
			(effects
				(font
					(size 1.27 1.27)
				)
			)
		)
		(duplicate_pad_numbers_are_jumpers no)
		(fp_line
			(start -0.7874 -0.4064)
			(end 0.7874 -0.4064)
			(stroke
				(width 0.1524)
				(type default)
			)
			(layer "F.SilkS")
		)
		(fp_line
			(start -0.7874 0.4064)
			(end -0.7874 -0.4064)
			(stroke
				(width 0.1524)
				(type default)
			)
			(layer "F.SilkS")
		)
		(fp_line
			(start 0.7874 -0.4064)
			(end 0.7874 0.4064)
			(stroke
				(width 0.1524)
				(type default)
			)
			(layer "F.SilkS")
		)
		(fp_line
			(start 0.7874 0.4064)
			(end -0.7874 0.4064)
			(stroke
				(width 0.1524)
				(type default)
			)
			(layer "F.SilkS")
		)
		(fp_line
			(start -0.67945 -0.305054)
			(end -0.12065 -0.305054)
			(stroke
				(width 0.1)
				(type default)
			)
			(layer "F.Fab")
		)
		(fp_line
			(start -0.67945 0.3048)
			(end -0.67945 -0.305054)
			(stroke
				(width 0.1)
				(type default)
			)
			(layer "F.Fab")
		)
		(fp_line
			(start -0.12065 -0.305054)
			(end -0.12065 -0.2794)
			(stroke
				(width 0.1)
				(type default)
			)
			(layer "F.Fab")
		)
		(fp_line
			(start -0.12065 -0.2794)
			(end 0.12065 -0.2794)
			(stroke
				(width 0.1)
				(type default)
			)
			(layer "F.Fab")
		)
		(fp_line
			(start -0.12065 0.2794)
			(end -0.12065 0.3048)
			(stroke
				(width 0.1)
				(type default)
			)
			(layer "F.Fab")
		)
		(fp_line
			(start -0.12065 0.3048)
			(end -0.67945 0.3048)
			(stroke
				(width 0.1)
				(type default)
			)
			(layer "F.Fab")
		)
		(fp_line
			(start 0.120396 0.2794)
			(end -0.12065 0.2794)
			(stroke
				(width 0.1)
				(type default)
			)
			(layer "F.Fab")
		)
		(fp_line
			(start 0.120396 0.3048)
			(end 0.120396 0.2794)
			(stroke
				(width 0.1)
				(type default)
			)
			(layer "F.Fab")
		)
		(fp_line
			(start 0.12065 -0.3048)
			(end 0.67945 -0.3048)
			(stroke
				(width 0.1)
				(type default)
			)
			(layer "F.Fab")
		)
		(fp_line
			(start 0.12065 -0.2794)
			(end 0.12065 -0.3048)
			(stroke
				(width 0.1)
				(type default)
			)
			(layer "F.Fab")
		)
		(fp_line
			(start 0.67945 -0.3048)
			(end 0.67945 0.3048)
			(stroke
				(width 0.1)
				(type default)
			)
			(layer "F.Fab")
		)
		(fp_line
			(start 0.67945 0.3048)
			(end 0.120396 0.3048)
			(stroke
				(width 0.1)
				(type default)
			)
			(layer "F.Fab")
		)
		(pad "1" smd circle
			(at -0.40005 0)
			(size 0 0)
			(layers "F.Cu" "F.Mask" "F.Paste")
			(net "NIC6_PEX_PWR_EN")
		)
		(pad "2" smd circle
			(at 0.40005 0)
			(size 0 0)
			(layers "F.Cu" "F.Mask" "F.Paste")
			(net "NIC6_PEX_PWR_EN_R")
		)
	)
)
